(kicad_pcb
	(version 20260206)
	(generator "pcbnew")
	(generator_version "10.0")
	(general
		(thickness 1.6)
		(legacy_teardrops no)
	)
	(paper "A4")
	(title_block
		(title "04192023_DAF0TMB3IC0_F0TG_MB_C_brd_V02_OCP.brd")
		(comment 1 "Grand Teton / footprints 8196-8202 of 8354")
	)
	(layers
		(0 "F.Cu" signal "TOP")
		(4 "In1.Cu" signal "GND")
		(6 "In2.Cu" signal "IN1")
		(8 "In3.Cu" signal "GND1")
		(10 "In4.Cu" signal "IN2")
		(12 "In5.Cu" signal "GND2")
		(14 "In6.Cu" signal "IN3")
		(16 "In7.Cu" signal "GND3")
		(18 "In8.Cu" signal "VCC")
		(20 "In9.Cu" signal "VCC1")
		(22 "In10.Cu" signal "GND4")
		(24 "In11.Cu" signal "IN4")
		(26 "In12.Cu" signal "GND5")
		(28 "In13.Cu" signal "IN5")
		(30 "In14.Cu" signal "GND6")
		(32 "In15.Cu" signal "IN6")
		(34 "In16.Cu" signal "GND7")
		(2 "B.Cu" signal "BOTTOM")
		(9 "F.Adhes" user "F.Adhesive")
		(11 "B.Adhes" user "B.Adhesive")
		(13 "F.Paste" user "Package Geometry/Pastemask Top")
		(15 "B.Paste" user "Package Geometry/Pastemask Bottom")
		(5 "F.SilkS" user "Ref Des/Silkscreen Top")
		(7 "B.SilkS" user "Ref Des/Silkscreen Bottom")
		(1 "F.Mask" user "Board Geometry/Soldermask Top")
		(3 "B.Mask" user "Board Geometry/Soldermask Bottom")
		(17 "Dwgs.User" user "User.Drawings")
		(19 "Cmts.User" user "User.Comments")
		(21 "Eco1.User" user "User.Eco1")
		(23 "Eco2.User" user "User.Eco2")
		(25 "Edge.Cuts" user "Board Geometry/Outline")
		(27 "Margin" user)
		(31 "F.CrtYd" user "Package Geometry/Place Bound Top")
		(29 "B.CrtYd" user "Package Geometry/Place Bound Bottom")
		(35 "F.Fab" user "Ref Des/Assembly Top")
		(33 "B.Fab" user "Ref Des/Assembly Bottom")
	)
	(footprint ""
		(layer "B.Cu")
		(at 171.577 -100.294948 -90)
		(property "Reference" "R6019"
			(at 0 0 90)
			(layer "B.SilkS")
			(hide yes)
			(effects
				(font
					(size 1.27 1.27)
				)
				(justify mirror)
			)
		)
		(property "Value" ""
			(at 0 0 90)
			(layer "B.Fab")
			(effects
				(font
					(size 1.27 1.27)
				)
				(justify mirror)
			)
		)
		(duplicate_pad_numbers_are_jumpers no)
		(fp_line
			(start -0.7874 0.4064)
			(end 0.7874 0.4064)
			(stroke
				(width 0.1524)
				(type default)
			)
			(layer "B.SilkS")
		)
		(fp_line
			(start 0.7874 0.4064)
			(end 0.7874 -0.4064)
			(stroke
				(width 0.1524)
				(type default)
			)
			(layer "B.SilkS")
		)
		(fp_line
			(start -0.7874 -0.4064)
			(end -0.7874 0.4064)
			(stroke
				(width 0.1524)
				(type default)
			)
			(layer "B.SilkS")
		)
		(fp_line
			(start 0.7874 -0.4064)
			(end -0.7874 -0.4064)
			(stroke
				(width 0.1524)
				(type default)
			)
			(layer "B.SilkS")
		)
		(fp_line
			(start -0.67945 0.3048)
			(end -0.120396 0.3048)
			(stroke
				(width 0.1)
				(type default)
			)
			(layer "B.Fab")
		)
		(fp_line
			(start -0.120396 0.3048)
			(end -0.120396 0.2794)
			(stroke
				(width 0.1)
				(type default)
			)
			(layer "B.Fab")
		)
		(fp_line
			(start 0.12065 0.3048)
			(end 0.67945 0.3048)
			(stroke
				(width 0.1)
				(type default)
			)
			(layer "B.Fab")
		)
		(fp_line
			(start 0.67945 0.3048)
			(end 0.67945 -0.305054)
			(stroke
				(width 0.1)
				(type default)
			)
			(layer "B.Fab")
		)
		(fp_line
			(start -0.120396 0.2794)
			(end 0.12065 0.2794)
			(stroke
				(width 0.1)
				(type default)
			)
			(layer "B.Fab")
		)
		(fp_line
			(start 0.12065 0.2794)
			(end 0.12065 0.3048)
			(stroke
				(width 0.1)
				(type default)
			)
			(layer "B.Fab")
		)
		(fp_line
			(start -0.12065 -0.2794)
			(end -0.12065 -0.3048)
			(stroke
				(width 0.1)
				(type default)
			)
			(layer "B.Fab")
		)
		(fp_line
			(start 0.12065 -0.2794)
			(end -0.12065 -0.2794)
			(stroke
				(width 0.1)
				(type default)
			)
			(layer "B.Fab")
		)
		(fp_line
			(start -0.67945 -0.3048)
			(end -0.67945 0.3048)
			(stroke
				(width 0.1)
				(type default)
			)
			(layer "B.Fab")
		)
		(fp_line
			(start -0.12065 -0.3048)
			(end -0.67945 -0.3048)
			(stroke
				(width 0.1)
				(type default)
			)
			(layer "B.Fab")
		)
		(fp_line
			(start 0.12065 -0.305054)
			(end 0.12065 -0.2794)
			(stroke
				(width 0.1)
				(type default)
			)
			(layer "B.Fab")
		)
		(fp_line
			(start 0.67945 -0.305054)
			(end 0.12065 -0.305054)
			(stroke
				(width 0.1)
				(type default)
			)
			(layer "B.Fab")
		)
		(pad "1" smd circle
			(at 0.40005 0 90)
			(size 0 0)
			(layers "B.Cu" "B.Mask" "B.Paste")
			(net "P3V3_AUX")
		)
		(pad "2" smd circle
			(at -0.40005 0 90)
			(size 0 0)
			(layers "B.Cu" "B.Mask" "B.Paste")
			(net "SGPIO_SCM_LD_<0>")
		)
	)
	(footprint ""
		(layer "B.Cu")
		(at 144.932654 -316.47511 180)
		(property "Reference" "R546"
			(at 0 0 0)
			(layer "B.SilkS")
			(hide yes)
			(effects
				(font
					(size 1.27 1.27)
				)
				(justify mirror)
			)
		)
		(property "Value" ""
			(at 0 0 0)
			(layer "B.Fab")
			(effects
				(font
					(size 1.27 1.27)
				)
				(justify mirror)
			)
		)
		(duplicate_pad_numbers_are_jumpers no)
		(fp_line
			(start 0.7874 0.4064)
			(end 0.7874 -0.4064)
			(stroke
				(width 0.1524)
				(type default)
			)
			(layer "B.SilkS")
		)
		(fp_line
			(start 0.7874 -0.4064)
			(end -0.7874 -0.4064)
			(stroke
				(width 0.1524)
				(type default)
			)
			(layer "B.SilkS")
		)
		(fp_line
			(start -0.7874 0.4064)
			(end 0.7874 0.4064)
			(stroke
				(width 0.1524)
				(type default)
			)
			(layer "B.SilkS")
		)
		(fp_line
			(start -0.7874 -0.4064)
			(end -0.7874 0.4064)
			(stroke
				(width 0.1524)
				(type default)
			)
			(layer "B.SilkS")
		)
		(fp_line
			(start 0.67945 0.3048)
			(end 0.67945 -0.305054)
			(stroke
				(width 0.1)
				(type default)
			)
			(layer "B.Fab")
		)
		(fp_line
			(start 0.67945 -0.305054)
			(end 0.12065 -0.305054)
			(stroke
				(width 0.1)
				(type default)
			)
			(layer "B.Fab")
		)
		(fp_line
			(start 0.12065 0.3048)
			(end 0.67945 0.3048)
			(stroke
				(width 0.1)
				(type default)
			)
			(layer "B.Fab")
		)
		(fp_line
			(start 0.12065 0.2794)
			(end 0.12065 0.3048)
			(stroke
				(width 0.1)
				(type default)
			)
			(layer "B.Fab")
		)
		(fp_line
			(start 0.12065 -0.2794)
			(end -0.12065 -0.2794)
			(stroke
				(width 0.1)
				(type default)
			)
			(layer "B.Fab")
		)
		(fp_line
			(start 0.12065 -0.305054)
			(end 0.12065 -0.2794)
			(stroke
				(width 0.1)
				(type default)
			)
			(layer "B.Fab")
		)
		(fp_line
			(start -0.120396 0.3048)
			(end -0.120396 0.2794)
			(stroke
				(width 0.1)
				(type default)
			)
			(layer "B.Fab")
		)
		(fp_line
			(start -0.120396 0.2794)
			(end 0.12065 0.2794)
			(stroke
				(width 0.1)
				(type default)
			)
			(layer "B.Fab")
		)
		(fp_line
			(start -0.12065 -0.2794)
			(end -0.12065 -0.3048)
			(stroke
				(width 0.1)
				(type default)
			)
			(layer "B.Fab")
		)
		(fp_line
			(start -0.12065 -0.3048)
			(end -0.67945 -0.3048)
			(stroke
				(width 0.1)
				(type default)
			)
			(layer "B.Fab")
		)
		(fp_line
			(start -0.67945 0.3048)
			(end -0.120396 0.3048)
			(stroke
				(width 0.1)
				(type default)
			)
			(layer "B.Fab")
		)
		(fp_line
			(start -0.67945 -0.3048)
			(end -0.67945 0.3048)
			(stroke
				(width 0.1)
				(type default)
			)
			(layer "B.Fab")
		)
		(pad "1" smd circle
			(at 0.40005 0)
			(size 0 0)
			(layers "B.Cu" "B.Mask" "B.Paste")
			(net "FM_BMC_TPM_PRES_N")
		)
		(pad "2" smd circle
			(at -0.40005 0)
			(size 0 0)
			(layers "B.Cu" "B.Mask" "B.Paste")
			(net "PVDD18_S5_P1")
		)
	)
	(footprint ""
		(layer "B.Cu")
		(at 66.745358 -390.560052 90)
		(property "Reference" "C262"
			(at 0 0 90)
			(layer "B.SilkS")
			(hide yes)
			(effects
				(font
					(size 1.27 1.27)
				)
				(justify mirror)
			)
		)
		(property "Value" ""
			(at 0 0 90)
			(layer "B.Fab")
			(effects
				(font
					(size 1.27 1.27)
				)
				(justify mirror)
			)
		)
		(duplicate_pad_numbers_are_jumpers no)
		(fp_line
			(start 0.7874 -0.4064)
			(end -0.7874 -0.4064)
			(stroke
				(width 0.1524)
				(type default)
			)
			(layer "B.SilkS")
		)
		(fp_line
			(start -0.7874 -0.4064)
			(end -0.7874 0.4064)
			(stroke
				(width 0.1524)
				(type default)
			)
			(layer "B.SilkS")
		)
		(fp_line
			(start 0.7874 0.4064)
			(end 0.7874 -0.4064)
			(stroke
				(width 0.1524)
				(type default)
			)
			(layer "B.SilkS")
		)
		(fp_line
			(start -0.7874 0.4064)
			(end 0.7874 0.4064)
			(stroke
				(width 0.1524)
				(type default)
			)
			(layer "B.SilkS")
		)
		(fp_line
			(start 0.67945 -0.305054)
			(end 0.12065 -0.305054)
			(stroke
				(width 0.1)
				(type default)
			)
			(layer "B.Fab")
		)
		(fp_line
			(start 0.12065 -0.305054)
			(end 0.12065 -0.2794)
			(stroke
				(width 0.1)
				(type default)
			)
			(layer "B.Fab")
		)
		(fp_line
			(start -0.12065 -0.3048)
			(end -0.67945 -0.3048)
			(stroke
				(width 0.1)
				(type default)
			)
			(layer "B.Fab")
		)
		(fp_line
			(start -0.67945 -0.3048)
			(end -0.67945 0.3048)
			(stroke
				(width 0.1)
				(type default)
			)
			(layer "B.Fab")
		)
		(fp_line
			(start 0.12065 -0.2794)
			(end -0.12065 -0.2794)
			(stroke
				(width 0.1)
				(type default)
			)
			(layer "B.Fab")
		)
		(fp_line
			(start -0.12065 -0.2794)
			(end -0.12065 -0.3048)
			(stroke
				(width 0.1)
				(type default)
			)
			(layer "B.Fab")
		)
		(fp_line
			(start 0.12065 0.2794)
			(end 0.12065 0.3048)
			(stroke
				(width 0.1)
				(type default)
			)
			(layer "B.Fab")
		)
		(fp_line
			(start -0.120396 0.2794)
			(end 0.12065 0.2794)
			(stroke
				(width 0.1)
				(type default)
			)
			(layer "B.Fab")
		)
		(fp_line
			(start 0.67945 0.3048)
			(end 0.67945 -0.305054)
			(stroke
				(width 0.1)
				(type default)
			)
			(layer "B.Fab")
		)
		(fp_line
			(start 0.12065 0.3048)
			(end 0.67945 0.3048)
			(stroke
				(width 0.1)
				(type default)
			)
			(layer "B.Fab")
		)
		(fp_line
			(start -0.120396 0.3048)
			(end -0.120396 0.2794)
			(stroke
				(width 0.1)
				(type default)
			)
			(layer "B.Fab")
		)
		(fp_line
			(start -0.67945 0.3048)
			(end -0.120396 0.3048)
			(stroke
				(width 0.1)
				(type default)
			)
			(layer "B.Fab")
		)
		(pad "1" smd circle
			(at 0.40005 0 270)
			(size 0 0)
			(layers "B.Cu" "B.Mask" "B.Paste")
			(net "P0V9_CPU1_RT0_2A")
		)
		(pad "2" smd circle
			(at -0.40005 0 270)
			(size 0 0)
			(layers "B.Cu" "B.Mask" "B.Paste")
			(net "GND")
		)
	)
	(footprint ""
		(layer "B.Cu")
		(at 355.944932 -396.150592 180)
		(property "Reference" "C658"
			(at 0 0 0)
			(layer "B.SilkS")
			(hide yes)
			(effects
				(font
					(size 1.27 1.27)
				)
				(justify mirror)
			)
		)
		(property "Value" ""
			(at 0 0 0)
			(layer "B.Fab")
			(effects
				(font
					(size 1.27 1.27)
				)
				(justify mirror)
			)
		)
		(duplicate_pad_numbers_are_jumpers no)
		(fp_line
			(start 0.299974 0.150114)
			(end 0.299974 -0.150114)
			(stroke
				(width 0.1)
				(type default)
			)
			(layer "B.Fab")
		)
		(fp_line
			(start 0.299974 -0.150114)
			(end -0.299974 -0.150114)
			(stroke
				(width 0.1)
				(type default)
			)
			(layer "B.Fab")
		)
		(fp_line
			(start -0.299974 0.150114)
			(end 0.299974 0.150114)
			(stroke
				(width 0.1)
				(type default)
			)
			(layer "B.Fab")
		)
		(fp_line
			(start -0.299974 -0.150114)
			(end -0.299974 0.150114)
			(stroke
				(width 0.1)
				(type default)
			)
			(layer "B.Fab")
		)
		(pad "1" smd rect
			(at 0.2667 0)
			(size 0.3048 0.381)
			(layers "B.Cu" "B.Mask" "B.Paste")
			(net "P0V9_CPU0_RT1_2A")
		)
		(pad "2" smd rect
			(at -0.2667 0)
			(size 0.3048 0.381)
			(layers "B.Cu" "B.Mask" "B.Paste")
			(net "GND")
		)
	)
	(footprint ""
		(layer "B.Cu")
		(at 216.142824 -328.032872 180)
		(property "Reference" "R1241"
			(at 0 0 0)
			(layer "B.SilkS")
			(hide yes)
			(effects
				(font
					(size 1.27 1.27)
				)
				(justify mirror)
			)
		)
		(property "Value" ""
			(at 0 0 0)
			(layer "B.Fab")
			(effects
				(font
					(size 1.27 1.27)
				)
				(justify mirror)
			)
		)
		(duplicate_pad_numbers_are_jumpers no)
		(fp_line
			(start 0.7874 0.4064)
			(end 0.7874 -0.4064)
			(stroke
				(width 0.1524)
				(type default)
			)
			(layer "B.SilkS")
		)
		(fp_line
			(start 0.7874 -0.4064)
			(end -0.7874 -0.4064)
			(stroke
				(width 0.1524)
				(type default)
			)
			(layer "B.SilkS")
		)
		(fp_line
			(start -0.7874 0.4064)
			(end 0.7874 0.4064)
			(stroke
				(width 0.1524)
				(type default)
			)
			(layer "B.SilkS")
		)
		(fp_line
			(start -0.7874 -0.4064)
			(end -0.7874 0.4064)
			(stroke
				(width 0.1524)
				(type default)
			)
			(layer "B.SilkS")
		)
		(fp_line
			(start 0.67945 0.3048)
			(end 0.67945 -0.305054)
			(stroke
				(width 0.1)
				(type default)
			)
			(layer "B.Fab")
		)
		(fp_line
			(start 0.67945 -0.305054)
			(end 0.12065 -0.305054)
			(stroke
				(width 0.1)
				(type default)
			)
			(layer "B.Fab")
		)
		(fp_line
			(start 0.12065 0.3048)
			(end 0.67945 0.3048)
			(stroke
				(width 0.1)
				(type default)
			)
			(layer "B.Fab")
		)
		(fp_line
			(start 0.12065 0.2794)
			(end 0.12065 0.3048)
			(stroke
				(width 0.1)
				(type default)
			)
			(layer "B.Fab")
		)
		(fp_line
			(start 0.12065 -0.2794)
			(end -0.12065 -0.2794)
			(stroke
				(width 0.1)
				(type default)
			)
			(layer "B.Fab")
		)
		(fp_line
			(start 0.12065 -0.305054)
			(end 0.12065 -0.2794)
			(stroke
				(width 0.1)
				(type default)
			)
			(layer "B.Fab")
		)
		(fp_line
			(start -0.120396 0.3048)
			(end -0.120396 0.2794)
			(stroke
				(width 0.1)
				(type default)
			)
			(layer "B.Fab")
		)
		(fp_line
			(start -0.120396 0.2794)
			(end 0.12065 0.2794)
			(stroke
				(width 0.1)
				(type default)
			)
			(layer "B.Fab")
		)
		(fp_line
			(start -0.12065 -0.2794)
			(end -0.12065 -0.3048)
			(stroke
				(width 0.1)
				(type default)
			)
			(layer "B.Fab")
		)
		(fp_line
			(start -0.12065 -0.3048)
			(end -0.67945 -0.3048)
			(stroke
				(width 0.1)
				(type default)
			)
			(layer "B.Fab")
		)
		(fp_line
			(start -0.67945 0.3048)
			(end -0.120396 0.3048)
			(stroke
				(width 0.1)
				(type default)
			)
			(layer "B.Fab")
		)
		(fp_line
			(start -0.67945 -0.3048)
			(end -0.67945 0.3048)
			(stroke
				(width 0.1)
				(type default)
			)
			(layer "B.Fab")
		)
		(pad "1" smd circle
			(at 0.40005 0)
			(size 0 0)
			(layers "B.Cu" "B.Mask" "B.Paste")
			(net "P3V3_AUX")
		)
		(pad "2" smd circle
			(at -0.40005 0)
			(size 0 0)
			(layers "B.Cu" "B.Mask" "B.Paste")
			(net "ADC128_2_A0")
		)
	)
	(footprint ""
		(layer "B.Cu")
		(at 20.32 -366.903)
		(property "Reference" "R1495"
			(at 0 0 0)
			(layer "B.SilkS")
			(hide yes)
			(effects
				(font
					(size 1.27 1.27)
				)
				(justify mirror)
			)
		)
		(property "Value" ""
			(at 0 0 0)
			(layer "B.Fab")
			(effects
				(font
					(size 1.27 1.27)
				)
				(justify mirror)
			)
		)
		(duplicate_pad_numbers_are_jumpers no)
		(fp_line
			(start -0.7874 -0.4064)
			(end -0.7874 0.4064)
			(stroke
				(width 0.1524)
				(type default)
			)
			(layer "B.SilkS")
		)
		(fp_line
			(start -0.7874 0.4064)
			(end 0.7874 0.4064)
			(stroke
				(width 0.1524)
				(type default)
			)
			(layer "B.SilkS")
		)
		(fp_line
			(start 0.7874 -0.4064)
			(end -0.7874 -0.4064)
			(stroke
				(width 0.1524)
				(type default)
			)
			(layer "B.SilkS")
		)
		(fp_line
			(start 0.7874 0.4064)
			(end 0.7874 -0.4064)
			(stroke
				(width 0.1524)
				(type default)
			)
			(layer "B.SilkS")
		)
		(fp_line
			(start -0.67945 -0.3048)
			(end -0.67945 0.3048)
			(stroke
				(width 0.1)
				(type default)
			)
			(layer "B.Fab")
		)
		(fp_line
			(start -0.67945 0.3048)
			(end -0.120396 0.3048)
			(stroke
				(width 0.1)
				(type default)
			)
			(layer "B.Fab")
		)
		(fp_line
			(start -0.12065 -0.3048)
			(end -0.67945 -0.3048)
			(stroke
				(width 0.1)
				(type default)
			)
			(layer "B.Fab")
		)
		(fp_line
			(start -0.12065 -0.2794)
			(end -0.12065 -0.3048)
			(stroke
				(width 0.1)
				(type default)
			)
			(layer "B.Fab")
		)
		(fp_line
			(start -0.120396 0.2794)
			(end 0.12065 0.2794)
			(stroke
				(width 0.1)
				(type default)
			)
			(layer "B.Fab")
		)
		(fp_line
			(start -0.120396 0.3048)
			(end -0.120396 0.2794)
			(stroke
				(width 0.1)
				(type default)
			)
			(layer "B.Fab")
		)
		(fp_line
			(start 0.12065 -0.305054)
			(end 0.12065 -0.2794)
			(stroke
				(width 0.1)
				(type default)
			)
			(layer "B.Fab")
		)
		(fp_line
			(start 0.12065 -0.2794)
			(end -0.12065 -0.2794)
			(stroke
				(width 0.1)
				(type default)
			)
			(layer "B.Fab")
		)
		(fp_line
			(start 0.12065 0.2794)
			(end 0.12065 0.3048)
			(stroke
				(width 0.1)
				(type default)
			)
			(layer "B.Fab")
		)
		(fp_line
			(start 0.12065 0.3048)
			(end 0.67945 0.3048)
			(stroke
				(width 0.1)
				(type default)
			)
			(layer "B.Fab")
		)
		(fp_line
			(start 0.67945 -0.305054)
			(end 0.12065 -0.305054)
			(stroke
				(width 0.1)
				(type default)
			)
			(layer "B.Fab")
		)
		(fp_line
			(start 0.67945 0.3048)
			(end 0.67945 -0.305054)
			(stroke
				(width 0.1)
				(type default)
			)
			(layer "B.Fab")
		)
		(pad "1" smd circle
			(at 0.40005 0 180)
			(size 0 0)
			(layers "B.Cu" "B.Mask" "B.Paste")
			(net "SMB_SCM_2_R1_SCL")
		)
		(pad "2" smd circle
			(at -0.40005 0 180)
			(size 0 0)
			(layers "B.Cu" "B.Mask" "B.Paste")
			(net "SMB_SCM_2_R2_SCL")
		)
	)
	(footprint ""
		(layer "B.Cu")
		(at 171.199048 -105.121202 180)
		(property "Reference" "R205"
			(at 0 0 0)
			(layer "B.SilkS")
			(hide yes)
			(effects
				(font
					(size 1.27 1.27)
				)
				(justify mirror)
			)
		)
		(property "Value" ""
			(at 0 0 0)
			(layer "B.Fab")
			(effects
				(font
					(size 1.27 1.27)
				)
				(justify mirror)
			)
		)
		(duplicate_pad_numbers_are_jumpers no)
		(fp_line
			(start 0.7874 0.4064)
			(end 0.7874 -0.4064)
			(stroke
				(width 0.1524)
				(type default)
			)
			(layer "B.SilkS")
		)
		(fp_line
			(start 0.7874 -0.4064)
			(end -0.7874 -0.4064)
			(stroke
				(width 0.1524)
				(type default)
			)
			(layer "B.SilkS")
		)
		(fp_line
			(start -0.7874 0.4064)
			(end 0.7874 0.4064)
			(stroke
				(width 0.1524)
				(type default)
			)
			(layer "B.SilkS")
		)
		(fp_line
			(start -0.7874 -0.4064)
			(end -0.7874 0.4064)
			(stroke
				(width 0.1524)
				(type default)
			)
			(layer "B.SilkS")
		)
		(fp_line
			(start 0.67945 0.3048)
			(end 0.67945 -0.305054)
			(stroke
				(width 0.1)
				(type default)
			)
			(layer "B.Fab")
		)
		(fp_line
			(start 0.67945 -0.305054)
			(end 0.12065 -0.305054)
			(stroke
				(width 0.1)
				(type default)
			)
			(layer "B.Fab")
		)
		(fp_line
			(start 0.12065 0.3048)
			(end 0.67945 0.3048)
			(stroke
				(width 0.1)
				(type default)
			)
			(layer "B.Fab")
		)
		(fp_line
			(start 0.12065 0.2794)
			(end 0.12065 0.3048)
			(stroke
				(width 0.1)
				(type default)
			)
			(layer "B.Fab")
		)
		(fp_line
			(start 0.12065 -0.2794)
			(end -0.12065 -0.2794)
			(stroke
				(width 0.1)
				(type default)
			)
			(layer "B.Fab")
		)
		(fp_line
			(start 0.12065 -0.305054)
			(end 0.12065 -0.2794)
			(stroke
				(width 0.1)
				(type default)
			)
			(layer "B.Fab")
		)
		(fp_line
			(start -0.120396 0.3048)
			(end -0.120396 0.2794)
			(stroke
				(width 0.1)
				(type default)
			)
			(layer "B.Fab")
		)
		(fp_line
			(start -0.120396 0.2794)
			(end 0.12065 0.2794)
			(stroke
				(width 0.1)
				(type default)
			)
			(layer "B.Fab")
		)
		(fp_line
			(start -0.12065 -0.2794)
			(end -0.12065 -0.3048)
			(stroke
				(width 0.1)
				(type default)
			)
			(layer "B.Fab")
		)
		(fp_line
			(start -0.12065 -0.3048)
			(end -0.67945 -0.3048)
			(stroke
				(width 0.1)
				(type default)
			)
			(layer "B.Fab")
		)
		(fp_line
			(start -0.67945 0.3048)
			(end -0.120396 0.3048)
			(stroke
				(width 0.1)
				(type default)
			)
			(layer "B.Fab")
		)
		(fp_line
			(start -0.67945 -0.3048)
			(end -0.67945 0.3048)
			(stroke
				(width 0.1)
				(type default)
			)
			(layer "B.Fab")
		)
		(pad "1" smd circle
			(at 0.40005 0)
			(size 0 0)
			(layers "B.Cu" "B.Mask" "B.Paste")
			(net "CPU1_XTRIG_L5")
		)
		(pad "2" smd circle
			(at -0.40005 0)
			(size 0 0)
			(layers "B.Cu" "B.Mask" "B.Paste")
			(net "FM_CPU1_XTRIG_L5")
		)
	)
)
